(kicad_pcb
	(version 20260206)
	(generator "pcbnew")
	(generator_version "10.0")
	(general
		(thickness 1.6)
		(legacy_teardrops no)
	)
	(paper "A4")
	(title_block
		(title "baseboard — 13948-1b.1110WZS1818.brd")
		(comment 1 "Honey Badger (Wiwynn) / footprints 2256-2262 of 2523")
	)
	(layers
		(0 "F.Cu" signal "TOP")
		(4 "In1.Cu" signal "L2GND")
		(6 "In2.Cu" signal "L3")
		(8 "In3.Cu" signal "L4VCC")
		(10 "In4.Cu" signal "L5VCC")
		(12 "In5.Cu" signal "L6")
		(14 "In6.Cu" signal "L7GND")
		(2 "B.Cu" signal "BOTTOM")
		(9 "F.Adhes" user "F.Adhesive")
		(11 "B.Adhes" user "B.Adhesive")
		(13 "F.Paste" user "Package Geometry/Pastemask Top")
		(15 "B.Paste" user "Package Geometry/Pastemask Bottom")
		(5 "F.SilkS" user "Ref Des/Silkscreen Top")
		(7 "B.SilkS" user "Ref Des/Silkscreen Bottom")
		(1 "F.Mask" user "Board Geometry/Soldermask Top")
		(3 "B.Mask" user "Board Geometry/Soldermask Bottom")
		(17 "Dwgs.User" user "User.Drawings")
		(19 "Cmts.User" user "User.Comments")
		(21 "Eco1.User" user "User.Eco1")
		(23 "Eco2.User" user "User.Eco2")
		(25 "Edge.Cuts" user "Board Geometry/Outline")
		(27 "Margin" user)
		(31 "F.CrtYd" user "Package Geometry/Place Bound Top")
		(29 "B.CrtYd" user "Package Geometry/Place Bound Bottom")
		(35 "F.Fab" user "Ref Des/Assembly Top")
		(33 "B.Fab" user "Ref Des/Assembly Bottom")
	)
	(footprint ""
		(layer "B.Cu")
		(at 325.374 -175.006)
		(property "Reference" "R5764"
			(at 0 0 0)
			(layer "B.SilkS")
			(hide yes)
			(effects
				(font
					(size 1.27 1.27)
				)
				(justify mirror)
			)
		)
		(property "Value" "5K6R2F-2-GP"
			(at -0.064008 -3.993896 0)
			(unlocked yes)
			(layer "B.Fab")
			(hide yes)
			(effects
				(font
					(size 1.016 1.016)
					(thickness 0.1524)
				)
				(justify mirror)
			)
		)
		(property "Device Type" "R402H16"
			(at -0.064008 -5.517896 0)
			(unlocked yes)
			(layer "B.Fab")
			(hide yes)
			(effects
				(font
					(size 1.016 1.016)
					(thickness 0.1524)
				)
				(justify mirror)
			)
		)
		(duplicate_pad_numbers_are_jumpers no)
		(fp_line
			(start -0.508 -0.9398)
			(end 0.508 -0.9398)
			(stroke
				(width 0.1524)
				(type default)
			)
			(layer "B.SilkS")
		)
		(fp_line
			(start 0.508 -0.9398)
			(end 0.508 0.9398)
			(stroke
				(width 0.1524)
				(type default)
			)
			(layer "B.SilkS")
		)
		(fp_rect
			(start 0.508 0.9398)
			(end -0.508 -0.9398)
			(stroke
				(width 0)
				(type default)
			)
			(fill no)
			(layer "B.CrtYd")
		)
		(fp_rect
			(start 0.508 0.9398)
			(end -0.508 -0.9398)
			(stroke
				(width 0)
				(type default)
			)
			(fill no)
			(layer "B.Fab")
		)
		(pad "1" smd custom
			(at 0 -0.4445 180)
			(size 0.1397 0.1397)
			(layers "B.Cu" "B.Mask" "B.Paste")
			(net "P12V")
			(options
				(clearance outline)
				(anchor circle)
			)
			(primitives
				(gr_poly
					(pts
						(arc
							(start -0.1778 0.2794)
							(mid -0.249642 0.249642)
							(end -0.2794 0.1778)
						)
						(arc
							(start -0.2794 -0.1778)
							(mid -0.249642 -0.249642)
							(end -0.1778 -0.2794)
						)
						(arc
							(start 0.1778 -0.2794)
							(mid 0.249642 -0.249642)
							(end 0.2794 -0.1778)
						)
						(arc
							(start 0.2794 0.1778)
							(mid 0.249642 0.249642)
							(end 0.1778 0.2794)
						)
					)
					(width 0)
					(fill yes)
				)
			)
		)
		(pad "2" smd custom
			(at 0 0.4445 180)
			(size 0.1397 0.1397)
			(layers "B.Cu" "B.Mask" "B.Paste")
			(net "ADC_12V")
			(options
				(clearance outline)
				(anchor circle)
			)
			(primitives
				(gr_poly
					(pts
						(arc
							(start -0.1778 0.2794)
							(mid -0.249642 0.249642)
							(end -0.2794 0.1778)
						)
						(arc
							(start -0.2794 -0.1778)
							(mid -0.249642 -0.249642)
							(end -0.1778 -0.2794)
						)
						(arc
							(start 0.1778 -0.2794)
							(mid 0.249642 -0.249642)
							(end 0.2794 -0.1778)
						)
						(arc
							(start 0.2794 0.1778)
							(mid 0.249642 0.249642)
							(end 0.1778 0.2794)
						)
					)
					(width 0)
					(fill yes)
				)
			)
		)
	)
	(footprint ""
		(layer "B.Cu")
		(at 108.020612 -213.868 -90)
		(property "Reference" "SR906"
			(at 0 0 90)
			(layer "B.SilkS")
			(hide yes)
			(effects
				(font
					(size 1.27 1.27)
				)
				(justify mirror)
			)
		)
		(property "Value" "4K7R2F-GP"
			(at -0.064008 -3.993896 270)
			(unlocked yes)
			(layer "B.Fab")
			(hide yes)
			(effects
				(font
					(size 1.016 1.016)
					(thickness 0.1524)
				)
				(justify mirror)
			)
		)
		(property "Device Type" "R402H16"
			(at -0.064008 -5.517896 270)
			(unlocked yes)
			(layer "B.Fab")
			(hide yes)
			(effects
				(font
					(size 1.016 1.016)
					(thickness 0.1524)
				)
				(justify mirror)
			)
		)
		(duplicate_pad_numbers_are_jumpers no)
		(fp_line
			(start -0.508 -0.9398)
			(end 0.508 -0.9398)
			(stroke
				(width 0.1524)
				(type default)
			)
			(layer "B.SilkS")
		)
		(fp_line
			(start 0.508 -0.9398)
			(end 0.508 0.9398)
			(stroke
				(width 0.1524)
				(type default)
			)
			(layer "B.SilkS")
		)
		(fp_rect
			(start 0.508 0.9398)
			(end -0.508 -0.9398)
			(stroke
				(width 0)
				(type default)
			)
			(fill no)
			(layer "B.CrtYd")
		)
		(fp_rect
			(start 0.508 0.9398)
			(end -0.508 -0.9398)
			(stroke
				(width 0)
				(type default)
			)
			(fill no)
			(layer "B.Fab")
		)
		(pad "1" smd custom
			(at 0 -0.4445 90)
			(size 0.1397 0.1397)
			(layers "B.Cu" "B.Mask" "B.Paste")
			(net "REDV_D1_B")
			(options
				(clearance outline)
				(anchor circle)
			)
			(primitives
				(gr_poly
					(pts
						(arc
							(start -0.1778 0.2794)
							(mid -0.249642 0.249642)
							(end -0.2794 0.1778)
						)
						(arc
							(start -0.2794 -0.1778)
							(mid -0.249642 -0.249642)
							(end -0.1778 -0.2794)
						)
						(arc
							(start 0.1778 -0.2794)
							(mid 0.249642 -0.249642)
							(end 0.2794 -0.1778)
						)
						(arc
							(start 0.2794 0.1778)
							(mid 0.249642 0.249642)
							(end 0.1778 0.2794)
						)
					)
					(width 0)
					(fill yes)
				)
			)
		)
		(pad "2" smd custom
			(at 0 0.4445 90)
			(size 0.1397 0.1397)
			(layers "B.Cu" "B.Mask" "B.Paste")
			(net "GND")
			(options
				(clearance outline)
				(anchor circle)
			)
			(primitives
				(gr_poly
					(pts
						(arc
							(start -0.1778 0.2794)
							(mid -0.249642 0.249642)
							(end -0.2794 0.1778)
						)
						(arc
							(start -0.2794 -0.1778)
							(mid -0.249642 -0.249642)
							(end -0.1778 -0.2794)
						)
						(arc
							(start 0.1778 -0.2794)
							(mid 0.249642 -0.249642)
							(end 0.2794 -0.1778)
						)
						(arc
							(start 0.2794 0.1778)
							(mid 0.249642 0.249642)
							(end 0.1778 0.2794)
						)
					)
					(width 0)
					(fill yes)
				)
			)
		)
	)
	(footprint ""
		(layer "B.Cu")
		(at 323.401944 -174.975012 180)
		(property "Reference" "C8084"
			(at 0 0 0)
			(layer "B.SilkS")
			(hide yes)
			(effects
				(font
					(size 1.27 1.27)
				)
				(justify mirror)
			)
		)
		(property "Value" "SCD1U25V2KX-2-GP"
			(at -1.1811 -2.7051 180)
			(unlocked yes)
			(layer "B.Fab")
			(hide yes)
			(effects
				(font
					(size 1.016 1.016)
					(thickness 0.1524)
				)
				(justify mirror)
			)
		)
		(property "Device Type" "C402H22"
			(at -1.1811 -4.2291 180)
			(unlocked yes)
			(layer "B.Fab")
			(hide yes)
			(effects
				(font
					(size 1.016 1.016)
					(thickness 0.1524)
				)
				(justify mirror)
			)
		)
		(duplicate_pad_numbers_are_jumpers no)
		(fp_rect
			(start 0.4318 0.9525)
			(end -0.4318 -0.9525)
			(stroke
				(width 0)
				(type default)
			)
			(fill no)
			(layer "B.CrtYd")
		)
		(fp_rect
			(start 0.4318 0.9525)
			(end -0.4318 -0.9525)
			(stroke
				(width 0)
				(type default)
			)
			(fill no)
			(layer "B.Fab")
		)
		(pad "1" smd custom
			(at 0 -0.4445)
			(size 0.1524 0.1524)
			(layers "B.Cu" "B.Mask" "B.Paste")
			(net "ADC_12V")
			(options
				(clearance outline)
				(anchor circle)
			)
			(primitives
				(gr_poly
					(pts
						(arc
							(start 0.3048 0.2032)
							(mid 0.275042 0.275042)
							(end 0.2032 0.3048)
						)
						(arc
							(start -0.2032 0.3048)
							(mid -0.275042 0.275042)
							(end -0.3048 0.2032)
						)
						(arc
							(start -0.3048 -0.2032)
							(mid -0.275042 -0.275042)
							(end -0.2032 -0.3048)
						)
						(arc
							(start 0.2032 -0.3048)
							(mid 0.275042 -0.275042)
							(end 0.3048 -0.2032)
						)
					)
					(width 0)
					(fill yes)
				)
			)
		)
		(pad "2" smd custom
			(at 0 0.4445)
			(size 0.1524 0.1524)
			(layers "B.Cu" "B.Mask" "B.Paste")
			(net "GND")
			(options
				(clearance outline)
				(anchor circle)
			)
			(primitives
				(gr_poly
					(pts
						(arc
							(start 0.3048 0.2032)
							(mid 0.275042 0.275042)
							(end 0.2032 0.3048)
						)
						(arc
							(start -0.2032 0.3048)
							(mid -0.275042 0.275042)
							(end -0.3048 0.2032)
						)
						(arc
							(start -0.3048 -0.2032)
							(mid -0.275042 -0.275042)
							(end -0.2032 -0.3048)
						)
						(arc
							(start 0.2032 -0.3048)
							(mid 0.275042 -0.275042)
							(end 0.3048 -0.2032)
						)
					)
					(width 0)
					(fill yes)
				)
			)
		)
	)
	(footprint ""
		(layer "B.Cu")
		(at 114.281966 -43.561 -90)
		(property "Reference" "SR587"
			(at 0 0 90)
			(layer "B.SilkS")
			(hide yes)
			(effects
				(font
					(size 1.27 1.27)
				)
				(justify mirror)
			)
		)
		(property "Value" "10KR2F-2-GP"
			(at -0.064008 -3.993896 270)
			(unlocked yes)
			(layer "B.Fab")
			(hide yes)
			(effects
				(font
					(size 1.016 1.016)
					(thickness 0.1524)
				)
				(justify mirror)
			)
		)
		(property "Device Type" "R402H16"
			(at -0.064008 -5.517896 270)
			(unlocked yes)
			(layer "B.Fab")
			(hide yes)
			(effects
				(font
					(size 1.016 1.016)
					(thickness 0.1524)
				)
				(justify mirror)
			)
		)
		(duplicate_pad_numbers_are_jumpers no)
		(fp_line
			(start -0.508 -0.9398)
			(end 0.508 -0.9398)
			(stroke
				(width 0.1524)
				(type default)
			)
			(layer "B.SilkS")
		)
		(fp_line
			(start 0.508 -0.9398)
			(end 0.508 0.9398)
			(stroke
				(width 0.1524)
				(type default)
			)
			(layer "B.SilkS")
		)
		(fp_rect
			(start 0.508 0.9398)
			(end -0.508 -0.9398)
			(stroke
				(width 0)
				(type default)
			)
			(fill no)
			(layer "B.CrtYd")
		)
		(fp_rect
			(start 0.508 0.9398)
			(end -0.508 -0.9398)
			(stroke
				(width 0)
				(type default)
			)
			(fill no)
			(layer "B.Fab")
		)
		(pad "1" smd custom
			(at 0 -0.4445 90)
			(size 0.1397 0.1397)
			(layers "B.Cu" "B.Mask" "B.Paste")
			(net "GND")
			(options
				(clearance outline)
				(anchor circle)
			)
			(primitives
				(gr_poly
					(pts
						(arc
							(start -0.1778 0.2794)
							(mid -0.249642 0.249642)
							(end -0.2794 0.1778)
						)
						(arc
							(start -0.2794 -0.1778)
							(mid -0.249642 -0.249642)
							(end -0.1778 -0.2794)
						)
						(arc
							(start 0.1778 -0.2794)
							(mid 0.249642 -0.249642)
							(end 0.2794 -0.1778)
						)
						(arc
							(start 0.2794 0.1778)
							(mid 0.249642 0.249642)
							(end 0.1778 0.2794)
						)
					)
					(width 0)
					(fill yes)
				)
			)
		)
		(pad "2" smd custom
			(at 0 0.4445 90)
			(size 0.1397 0.1397)
			(layers "B.Cu" "B.Mask" "B.Paste")
			(net "IOC_CLK_SEL1")
			(options
				(clearance outline)
				(anchor circle)
			)
			(primitives
				(gr_poly
					(pts
						(arc
							(start -0.1778 0.2794)
							(mid -0.249642 0.249642)
							(end -0.2794 0.1778)
						)
						(arc
							(start -0.2794 -0.1778)
							(mid -0.249642 -0.249642)
							(end -0.1778 -0.2794)
						)
						(arc
							(start 0.1778 -0.2794)
							(mid 0.249642 -0.249642)
							(end 0.2794 -0.1778)
						)
						(arc
							(start 0.2794 0.1778)
							(mid 0.249642 0.249642)
							(end 0.1778 0.2794)
						)
					)
					(width 0)
					(fill yes)
				)
			)
		)
	)
	(footprint ""
		(layer "B.Cu")
		(at 126.600966 -33.401)
		(property "Reference" "SC932"
			(at 0 0 0)
			(layer "B.SilkS")
			(hide yes)
			(effects
				(font
					(size 1.27 1.27)
				)
				(justify mirror)
			)
		)
		(property "Value" "SC10U6D3V5KX-4GP"
			(at 0.0762 -6.1214 0)
			(unlocked yes)
			(layer "B.Fab")
			(hide yes)
			(effects
				(font
					(size 1.016 1.016)
					(thickness 0.1524)
				)
				(justify mirror)
			)
		)
		(property "Device Type" "C805H58"
			(at 0.0762 -8.1534 0)
			(unlocked yes)
			(layer "B.Fab")
			(hide yes)
			(effects
				(font
					(size 1.016 1.016)
					(thickness 0.1524)
				)
				(justify mirror)
			)
		)
		(duplicate_pad_numbers_are_jumpers no)
		(fp_line
			(start -0.635 0)
			(end 0.635 0)
			(stroke
				(width 0.508)
				(type default)
			)
			(layer "B.SilkS")
		)
		(fp_rect
			(start 0.9652 1.778)
			(end -0.9652 -1.778)
			(stroke
				(width 0)
				(type default)
			)
			(fill no)
			(layer "B.CrtYd")
		)
		(fp_poly
			(pts
				(xy 0.9652 -1.778) (xy -0.9652 -1.778) (xy -0.9652 1.778) (xy 0.9652 1.778)
			)
			(stroke
				(width 0)
				(type default)
			)
			(fill no)
			(layer "B.Fab")
		)
		(pad "1" smd rect
			(at 0 -0.9652 180)
			(size 1.397 1.143)
			(layers "B.Cu" "B.Mask" "B.Paste")
			(net "PLL_VDD")
		)
		(pad "2" smd rect
			(at 0 0.9652 180)
			(size 1.397 1.143)
			(layers "B.Cu" "B.Mask" "B.Paste")
			(net "GND")
		)
	)
	(footprint ""
		(layer "B.Cu")
		(at 109.352842 -82.621882 180)
		(property "Reference" "SR769"
			(at 0 0 0)
			(layer "B.SilkS")
			(hide yes)
			(effects
				(font
					(size 1.27 1.27)
				)
				(justify mirror)
			)
		)
		(property "Value" "4K75R2F-1-GP"
			(at -0.064008 -3.993896 180)
			(unlocked yes)
			(layer "B.Fab")
			(hide yes)
			(effects
				(font
					(size 1.016 1.016)
					(thickness 0.1524)
				)
				(justify mirror)
			)
		)
		(property "Device Type" "R402H16"
			(at -0.064008 -5.517896 180)
			(unlocked yes)
			(layer "B.Fab")
			(hide yes)
			(effects
				(font
					(size 1.016 1.016)
					(thickness 0.1524)
				)
				(justify mirror)
			)
		)
		(duplicate_pad_numbers_are_jumpers no)
		(fp_line
			(start 0.508 -0.9398)
			(end 0.508 0.9398)
			(stroke
				(width 0.1524)
				(type default)
			)
			(layer "B.SilkS")
		)
		(fp_line
			(start -0.508 -0.9398)
			(end 0.508 -0.9398)
			(stroke
				(width 0.1524)
				(type default)
			)
			(layer "B.SilkS")
		)
		(fp_rect
			(start 0.508 0.9398)
			(end -0.508 -0.9398)
			(stroke
				(width 0)
				(type default)
			)
			(fill no)
			(layer "B.CrtYd")
		)
		(fp_rect
			(start 0.508 0.9398)
			(end -0.508 -0.9398)
			(stroke
				(width 0)
				(type default)
			)
			(fill no)
			(layer "B.Fab")
		)
		(pad "1" smd custom
			(at 0 -0.4445)
			(size 0.1397 0.1397)
			(layers "B.Cu" "B.Mask" "B.Paste")
			(net "GND")
			(options
				(clearance outline)
				(anchor circle)
			)
			(primitives
				(gr_poly
					(pts
						(arc
							(start -0.1778 0.2794)
							(mid -0.249642 0.249642)
							(end -0.2794 0.1778)
						)
						(arc
							(start -0.2794 -0.1778)
							(mid -0.249642 -0.249642)
							(end -0.1778 -0.2794)
						)
						(arc
							(start 0.1778 -0.2794)
							(mid 0.249642 -0.249642)
							(end 0.2794 -0.1778)
						)
						(arc
							(start 0.2794 0.1778)
							(mid 0.249642 0.249642)
							(end 0.1778 0.2794)
						)
					)
					(width 0)
					(fill yes)
				)
			)
		)
		(pad "2" smd custom
			(at 0 0.4445)
			(size 0.1397 0.1397)
			(layers "B.Cu" "B.Mask" "B.Paste")
			(net "EXP_ADC_IN0")
			(options
				(clearance outline)
				(anchor circle)
			)
			(primitives
				(gr_poly
					(pts
						(arc
							(start -0.1778 0.2794)
							(mid -0.249642 0.249642)
							(end -0.2794 0.1778)
						)
						(arc
							(start -0.2794 -0.1778)
							(mid -0.249642 -0.249642)
							(end -0.1778 -0.2794)
						)
						(arc
							(start 0.1778 -0.2794)
							(mid 0.249642 -0.249642)
							(end 0.2794 -0.1778)
						)
						(arc
							(start 0.2794 0.1778)
							(mid 0.249642 0.249642)
							(end 0.1778 0.2794)
						)
					)
					(width 0)
					(fill yes)
				)
			)
		)
	)
	(footprint ""
		(layer "B.Cu")
		(at 320.167 -162.433 180)
		(property "Reference" "R439"
			(at 0 0 0)
			(layer "B.SilkS")
			(hide yes)
			(effects
				(font
					(size 1.27 1.27)
				)
				(justify mirror)
			)
		)
		(property "Value" "10KR2F-2-GP"
			(at -0.064008 -3.993896 180)
			(unlocked yes)
			(layer "B.Fab")
			(hide yes)
			(effects
				(font
					(size 1.016 1.016)
					(thickness 0.1524)
				)
				(justify mirror)
			)
		)
		(property "Device Type" "R402H16"
			(at -0.064008 -5.517896 180)
			(unlocked yes)
			(layer "B.Fab")
			(hide yes)
			(effects
				(font
					(size 1.016 1.016)
					(thickness 0.1524)
				)
				(justify mirror)
			)
		)
		(duplicate_pad_numbers_are_jumpers no)
		(fp_line
			(start 0.508 -0.9398)
			(end 0.508 0.9398)
			(stroke
				(width 0.1524)
				(type default)
			)
			(layer "B.SilkS")
		)
		(fp_line
			(start -0.508 -0.9398)
			(end 0.508 -0.9398)
			(stroke
				(width 0.1524)
				(type default)
			)
			(layer "B.SilkS")
		)
		(fp_rect
			(start 0.508 0.9398)
			(end -0.508 -0.9398)
			(stroke
				(width 0)
				(type default)
			)
			(fill no)
			(layer "B.CrtYd")
		)
		(fp_rect
			(start 0.508 0.9398)
			(end -0.508 -0.9398)
			(stroke
				(width 0)
				(type default)
			)
			(fill no)
			(layer "B.Fab")
		)
		(pad "1" smd custom
			(at 0 -0.4445)
			(size 0.1397 0.1397)
			(layers "B.Cu" "B.Mask" "B.Paste")
			(net "P3V3_STBY")
			(options
				(clearance outline)
				(anchor circle)
			)
			(primitives
				(gr_poly
					(pts
						(arc
							(start -0.1778 0.2794)
							(mid -0.249642 0.249642)
							(end -0.2794 0.1778)
						)
						(arc
							(start -0.2794 -0.1778)
							(mid -0.249642 -0.249642)
							(end -0.1778 -0.2794)
						)
						(arc
							(start 0.1778 -0.2794)
							(mid 0.249642 -0.249642)
							(end 0.2794 -0.1778)
						)
						(arc
							(start 0.2794 0.1778)
							(mid 0.249642 0.249642)
							(end 0.1778 0.2794)
						)
					)
					(width 0)
					(fill yes)
				)
			)
		)
		(pad "2" smd custom
			(at 0 0.4445)
			(size 0.1397 0.1397)
			(layers "B.Cu" "B.Mask" "B.Paste")
			(net "NIC_SMBUS_SCL")
			(options
				(clearance outline)
				(anchor circle)
			)
			(primitives
				(gr_poly
					(pts
						(arc
							(start -0.1778 0.2794)
							(mid -0.249642 0.249642)
							(end -0.2794 0.1778)
						)
						(arc
							(start -0.2794 -0.1778)
							(mid -0.249642 -0.249642)
							(end -0.1778 -0.2794)
						)
						(arc
							(start 0.1778 -0.2794)
							(mid 0.249642 -0.249642)
							(end 0.2794 -0.1778)
						)
						(arc
							(start 0.2794 0.1778)
							(mid 0.249642 0.249642)
							(end 0.1778 0.2794)
						)
					)
					(width 0)
					(fill yes)
				)
			)
		)
	)
)
